# S9S_MB_2U (Grand Teton) — schematic netlist excerpt (pin names and nets, part order shuffled) for the footprints in the layout excerpt that follows; sources: Cadence DE-HDL packaged netlist, KiCad conversion of 03242023_DA0F0TMBIJ0_F0T_Motherboard_J_brd_V01_OCP.brd

PC178  Q_CAP  100NF 50V 10% X7R  pkg C0402  page 276 : A = SW_PVCCFA_EHV_CPU0_BOOT1_R ; B = SW_PVCCFA_EHV_CPU0_BOOTR1
C288  Q_CAP  22UF 4V 20% X6S  pkg C0402  page 77 : A = PVCCIN_CPU1 ; B = GND

(kicad_pcb
	(version 20260206)
	(generator "pcbnew")
	(generator_version "10.0")
	(general
		(thickness 1.6)
		(legacy_teardrops no)
	)
	(paper "A4")
	(title_block
		(title "03242023_DA0F0TMBIJ0_F0T_Motherboard_J_brd_V01_OCP.brd")
		(comment 1 "Grand Teton / footprints 1922-1923 of 6105")
	)
	(layers
		(0 "F.Cu" signal "TOP")
		(4 "In1.Cu" signal "GND")
		(6 "In2.Cu" signal "IN1")
		(8 "In3.Cu" signal "GND1")
		(10 "In4.Cu" signal "IN2")
		(12 "In5.Cu" signal "GND2")
		(14 "In6.Cu" signal "IN3")
		(16 "In7.Cu" signal "GND3")
		(18 "In8.Cu" signal "VCC")
		(20 "In9.Cu" signal "VCC1")
		(22 "In10.Cu" signal "GND4")
		(24 "In11.Cu" signal "IN4")
		(26 "In12.Cu" signal "GND5")
		(28 "In13.Cu" signal "IN5")
		(30 "In14.Cu" signal "GND6")
		(32 "In15.Cu" signal "IN6")
		(34 "In16.Cu" signal "GND7")
		(2 "B.Cu" signal "BOTTOM")
		(9 "F.Adhes" user "F.Adhesive")
		(11 "B.Adhes" user "B.Adhesive")
		(13 "F.Paste" user "Package Geometry/Pastemask Top")
		(15 "B.Paste" user "Package Geometry/Pastemask Bottom")
		(5 "F.SilkS" user "Ref Des/Silkscreen Top")
		(7 "B.SilkS" user "Ref Des/Silkscreen Bottom")
		(1 "F.Mask" user "Board Geometry/Soldermask Top")
		(3 "B.Mask" user "Board Geometry/Soldermask Bottom")
		(17 "Dwgs.User" user "User.Drawings")
		(19 "Cmts.User" user "User.Comments")
		(21 "Eco1.User" user "User.Eco1")
		(23 "Eco2.User" user "User.Eco2")
		(25 "Edge.Cuts" user "Board Geometry/Outline")
		(27 "Margin" user)
		(31 "F.CrtYd" user "Package Geometry/Place Bound Top")
		(29 "B.CrtYd" user "Package Geometry/Place Bound Bottom")
		(35 "F.Fab" user "Ref Des/Assembly Top")
		(33 "B.Fab" user "Ref Des/Assembly Bottom")
	)
	(footprint ""
		(layer "F.Cu")
		(at 422.740074 -151.119586 180)
		(property "Reference" "PC178"
			(at 0 0 180)
			(layer "F.SilkS")
			(hide yes)
			(effects
				(font
					(size 1.27 1.27)
				)
			)
		)
		(property "Value" ""
			(at 0 0 180)
			(layer "F.Fab")
			(effects
				(font
					(size 1.27 1.27)
				)
			)
		)
		(duplicate_pad_numbers_are_jumpers no)
		(fp_line
			(start 0.7874 0.4064)
			(end -0.7874 0.4064)
			(stroke
				(width 0.1524)
				(type default)
			)
			(layer "F.SilkS")
		)
		(fp_line
			(start 0.7874 -0.4064)
			(end 0.7874 0.4064)
			(stroke
				(width 0.1524)
				(type default)
			)
			(layer "F.SilkS")
		)
		(fp_line
			(start -0.7874 0.4064)
			(end -0.7874 -0.4064)
			(stroke
				(width 0.1524)
				(type default)
			)
			(layer "F.SilkS")
		)
		(fp_line
			(start -0.7874 -0.4064)
			(end 0.7874 -0.4064)
			(stroke
				(width 0.1524)
				(type default)
			)
			(layer "F.SilkS")
		)
		(fp_line
			(start 0.67945 0.3048)
			(end 0.120396 0.3048)
			(stroke
				(width 0.1)
				(type default)
			)
			(layer "F.Fab")
		)
		(fp_line
			(start 0.67945 -0.3048)
			(end 0.67945 0.3048)
			(stroke
				(width 0.1)
				(type default)
			)
			(layer "F.Fab")
		)
		(fp_line
			(start 0.12065 -0.2794)
			(end 0.12065 -0.3048)
			(stroke
				(width 0.1)
				(type default)
			)
			(layer "F.Fab")
		)
		(fp_line
			(start 0.12065 -0.3048)
			(end 0.67945 -0.3048)
			(stroke
				(width 0.1)
				(type default)
			)
			(layer "F.Fab")
		)
		(fp_line
			(start 0.120396 0.3048)
			(end 0.120396 0.2794)
			(stroke
				(width 0.1)
				(type default)
			)
			(layer "F.Fab")
		)
		(fp_line
			(start 0.120396 0.2794)
			(end -0.12065 0.2794)
			(stroke
				(width 0.1)
				(type default)
			)
			(layer "F.Fab")
		)
		(fp_line
			(start -0.12065 0.3048)
			(end -0.67945 0.3048)
			(stroke
				(width 0.1)
				(type default)
			)
			(layer "F.Fab")
		)
		(fp_line
			(start -0.12065 0.2794)
			(end -0.12065 0.3048)
			(stroke
				(width 0.1)
				(type default)
			)
			(layer "F.Fab")
		)
		(fp_line
			(start -0.12065 -0.2794)
			(end 0.12065 -0.2794)
			(stroke
				(width 0.1)
				(type default)
			)
			(layer "F.Fab")
		)
		(fp_line
			(start -0.12065 -0.305054)
			(end -0.12065 -0.2794)
			(stroke
				(width 0.1)
				(type default)
			)
			(layer "F.Fab")
		)
		(fp_line
			(start -0.67945 0.3048)
			(end -0.67945 -0.305054)
			(stroke
				(width 0.1)
				(type default)
			)
			(layer "F.Fab")
		)
		(fp_line
			(start -0.67945 -0.305054)
			(end -0.12065 -0.305054)
			(stroke
				(width 0.1)
				(type default)
			)
			(layer "F.Fab")
		)
		(pad "1" smd circle
			(at -0.40005 0 180)
			(size 0 0)
			(layers "F.Cu" "F.Mask" "F.Paste")
			(net "SW_PVCCFA_EHV_CPU0_BOOT1_R")
		)
		(pad "2" smd circle
			(at 0.40005 0 180)
			(size 0 0)
			(layers "F.Cu" "F.Mask" "F.Paste")
			(net "SW_PVCCFA_EHV_CPU0_BOOTR1")
		)
	)
	(footprint ""
		(layer "F.Cu")
		(at 107.296204 -244.032024 90)
		(property "Reference" "C288"
			(at 0 0 90)
			(layer "F.SilkS")
			(hide yes)
			(effects
				(font
					(size 1.27 1.27)
				)
			)
		)
		(property "Value" ""
			(at 0 0 90)
			(layer "F.Fab")
			(effects
				(font
					(size 1.27 1.27)
				)
			)
		)
		(duplicate_pad_numbers_are_jumpers no)
		(fp_line
			(start 0.7874 -0.4064)
			(end 0.7874 0.4064)
			(stroke
				(width 0.1524)
				(type default)
			)
			(layer "F.SilkS")
		)
		(fp_line
			(start -0.7874 -0.4064)
			(end 0.7874 -0.4064)
			(stroke
				(width 0.1524)
				(type default)
			)
			(layer "F.SilkS")
		)
		(fp_line
			(start 0.7874 0.4064)
			(end -0.7874 0.4064)
			(stroke
				(width 0.1524)
				(type default)
			)
			(layer "F.SilkS")
		)
		(fp_line
			(start -0.7874 0.4064)
			(end -0.7874 -0.4064)
			(stroke
				(width 0.1524)
				(type default)
			)
			(layer "F.SilkS")
		)
		(fp_line
			(start -0.12065 -0.305054)
			(end -0.12065 -0.2794)
			(stroke
				(width 0.1)
				(type default)
			)
			(layer "F.Fab")
		)
		(fp_line
			(start -0.67945 -0.305054)
			(end -0.12065 -0.305054)
			(stroke
				(width 0.1)
				(type default)
			)
			(layer "F.Fab")
		)
		(fp_line
			(start 0.67945 -0.3048)
			(end 0.67945 0.3048)
			(stroke
				(width 0.1)
				(type default)
			)
			(layer "F.Fab")
		)
		(fp_line
			(start 0.12065 -0.3048)
			(end 0.67945 -0.3048)
			(stroke
				(width 0.1)
				(type default)
			)
			(layer "F.Fab")
		)
		(fp_line
			(start 0.12065 -0.2794)
			(end 0.12065 -0.3048)
			(stroke
				(width 0.1)
				(type default)
			)
			(layer "F.Fab")
		)
		(fp_line
			(start -0.12065 -0.2794)
			(end 0.12065 -0.2794)
			(stroke
				(width 0.1)
				(type default)
			)
			(layer "F.Fab")
		)
		(fp_line
			(start 0.120396 0.2794)
			(end -0.12065 0.2794)
			(stroke
				(width 0.1)
				(type default)
			)
			(layer "F.Fab")
		)
		(fp_line
			(start -0.12065 0.2794)
			(end -0.12065 0.3048)
			(stroke
				(width 0.1)
				(type default)
			)
			(layer "F.Fab")
		)
		(fp_line
			(start 0.67945 0.3048)
			(end 0.120396 0.3048)
			(stroke
				(width 0.1)
				(type default)
			)
			(layer "F.Fab")
		)
		(fp_line
			(start 0.120396 0.3048)
			(end 0.120396 0.2794)
			(stroke
				(width 0.1)
				(type default)
			)
			(layer "F.Fab")
		)
		(fp_line
			(start -0.12065 0.3048)
			(end -0.67945 0.3048)
			(stroke
				(width 0.1)
				(type default)
			)
			(layer "F.Fab")
		)
		(fp_line
			(start -0.67945 0.3048)
			(end -0.67945 -0.305054)
			(stroke
				(width 0.1)
				(type default)
			)
			(layer "F.Fab")
		)
		(pad "1" smd circle
			(at -0.40005 0 90)
			(size 0 0)
			(layers "F.Cu" "F.Mask" "F.Paste")
			(net "PVCCIN_CPU1")
		)
		(pad "2" smd circle
			(at 0.40005 0 90)
			(size 0 0)
			(layers "F.Cu" "F.Mask" "F.Paste")
			(net "GND")
		)
	)
)
